(kicad_pcb
	(version 20241229)
	(generator "pcbnew")
	(generator_version "9.0")
	(general
		(thickness 1.6642)
		(legacy_teardrops no)
	)
	(paper "A3")
	(title_block
		(title "PolarFire SoM")
		(date "2025-07-22")
		(rev "1.1.4")
		(company "Antmicro Ltd")
		(comment 1 "www.antmicro.com")
		(comment 9 "footprints 254-258 of 470")
	)
	(layers
		(0 "F.Cu" mixed)
		(4 "In1.Cu" power)
		(6 "In2.Cu" signal)
		(8 "In3.Cu" power)
		(10 "In4.Cu" signal)
		(12 "In5.Cu" power)
		(14 "In6.Cu" power)
		(16 "In7.Cu" signal)
		(18 "In8.Cu" power)
		(20 "In9.Cu" signal)
		(22 "In10.Cu" power)
		(24 "In11.Cu" signal)
		(26 "In12.Cu" signal)
		(2 "B.Cu" mixed)
		(9 "F.Adhes" user "F.Adhesive")
		(11 "B.Adhes" user "B.Adhesive")
		(13 "F.Paste" user)
		(15 "B.Paste" user)
		(5 "F.SilkS" user "F.Silkscreen")
		(7 "B.SilkS" user "B.Silkscreen")
		(1 "F.Mask" user)
		(3 "B.Mask" user)
		(17 "Dwgs.User" user "User.Drawings")
		(19 "Cmts.User" user "User.Comments")
		(21 "Eco1.User" user "User.Eco1")
		(23 "Eco2.User" user "User.Eco2")
		(25 "Edge.Cuts" user)
		(27 "Margin" user)
		(31 "F.CrtYd" user "F.Courtyard")
		(29 "B.CrtYd" user "B.Courtyard")
		(35 "F.Fab" user)
		(33 "B.Fab" user)
	)
	(footprint "antmicro-footprints:R_0402_1005Metric"
		(layer "B.Cu")
		(at 210.1925 132.347)
		(descr "Resistor SMD 0402")
		(tags "resistor SMD 0402")
		(property "Reference" "R34"
			(at -0.8425 0.628 180)
			(layer "B.SilkS")
			(effects
				(font
					(size 0.7 0.7)
					(thickness 0.15)
				)
				(justify left bottom mirror)
			)
		)
		(property "Value" "R_49k9_0402"
			(at -1.011843 -1.772047 180)
			(layer "B.Fab")
			(hide yes)
			(effects
				(font
					(size 0.7 0.7)
					(thickness 0.15)
				)
				(justify left bottom mirror)
			)
		)
		(property "Datasheet" "https://www.bourns.com/docs/product-datasheets/cr.pdf"
			(at 0 0 0)
			(layer "F.Fab")
			(hide yes)
			(effects
				(font
					(size 1.27 1.27)
					(thickness 0.15)
				)
			)
		)
		(property "Description" "SMD Chip Resistor, 49.9 kohm, ± 1%, 63 mW, 0402 [1005 Metric], Thick Film, General Purpose"
			(at 0 0 0)
			(layer "F.Fab")
			(hide yes)
			(effects
				(font
					(size 1.27 1.27)
					(thickness 0.15)
				)
			)
		)
		(property "Author" "Antmicro"
			(at 0 0 0)
			(layer "B.Fab")
			(hide yes)
			(effects
				(font
					(size 1 1)
					(thickness 0.15)
				)
				(justify mirror)
			)
		)
		(property "License" "Apache-2.0"
			(at 0 0 0)
			(layer "B.Fab")
			(hide yes)
			(effects
				(font
					(size 1 1)
					(thickness 0.15)
				)
				(justify mirror)
			)
		)
		(property "MPN" "CR0402-FX-4992GLF"
			(at 0 0 0)
			(layer "B.Fab")
			(hide yes)
			(effects
				(font
					(size 1 1)
					(thickness 0.15)
				)
				(justify mirror)
			)
		)
		(property "Manufacturer" "Bourns"
			(at 0 0 0)
			(layer "B.Fab")
			(hide yes)
			(effects
				(font
					(size 1 1)
					(thickness 0.15)
				)
				(justify mirror)
			)
		)
		(property "Public" ""
			(at 0 0 0)
			(layer "B.Fab")
			(hide yes)
			(effects
				(font
					(size 1 1)
					(thickness 0.15)
				)
				(justify mirror)
			)
		)
		(property "Tolerance" "1%"
			(at 0 0 0)
			(layer "B.Fab")
			(hide yes)
			(effects
				(font
					(size 1 1)
					(thickness 0.15)
				)
				(justify mirror)
			)
		)
		(property "Val" "49k9"
			(at 0 0 0)
			(layer "B.Fab")
			(hide yes)
			(effects
				(font
					(size 1 1)
					(thickness 0.15)
				)
				(justify mirror)
			)
		)
		(sheetname "/Memory/")
		(sheetfile "memory.kicad_sch")
		(attr smd)
		(fp_rect
			(start -0.925 0.47)
			(end 0.925 -0.47)
			(stroke
				(width 0.05)
				(type default)
			)
			(fill no)
			(layer "B.CrtYd")
		)
		(fp_rect
			(start -0.5 0.25)
			(end 0.5 -0.25)
			(stroke
				(width 0.15)
				(type solid)
			)
			(fill no)
			(layer "B.Fab")
		)
		(fp_text user "License: Apache-2.0"
			(at -0.95 -5.169 180)
			(layer "B.Fab")
			(effects
				(font
					(size 0.7 0.7)
					(thickness 0.15)
				)
				(justify left bottom mirror)
			)
		)
		(fp_text user "Author: Antmicro"
			(at -0.95 -4.169 180)
			(layer "B.Fab")
			(effects
				(font
					(size 0.7 0.7)
					(thickness 0.15)
				)
				(justify left bottom mirror)
			)
		)
		(fp_text user "${REFERENCE}"
			(at -0.95 -3.168 180)
			(layer "B.Fab")
			(effects
				(font
					(size 0.7 0.7)
					(thickness 0.15)
				)
				(justify left bottom mirror)
			)
		)
		(pad "1" smd roundrect
			(at -0.48 0)
			(size 0.59 0.64)
			(layers "B.Cu" "B.Mask" "B.Paste")
			(roundrect_rratio 0.25)
			(net 250 "/FPGA MSSIO/EMMC.DAT4")
			(pintype "passive")
		)
		(pad "2" smd roundrect
			(at 0.48 0)
			(size 0.59 0.64)
			(layers "B.Cu" "B.Mask" "B.Paste")
			(roundrect_rratio 0.25)
			(net 137 "SD_VDD")
			(pintype "passive")
		)
	)
	(footprint "antmicro-footprints:C_0603_1608Metric"
		(layer "B.Cu")
		(at 206.09 131.6 90)
		(descr "Capacitor SMD 0603")
		(tags "capacitor 0603")
		(property "Reference" "C67"
			(at 1.25 0.36 90)
			(layer "B.SilkS")
			(effects
				(font
					(size 0.7 0.7)
					(thickness 0.15)
				)
				(justify right bottom mirror)
			)
		)
		(property "Value" "C_47u_0603"
			(at -1.42757 -1.770288 90)
			(layer "B.Fab")
			(hide yes)
			(effects
				(font
					(size 0.7 0.7)
					(thickness 0.15)
				)
				(justify right bottom mirror)
			)
		)
		(property "Datasheet" "https://www.murata.com/products/productdetail?partno=GRM188R60J476ME15%23"
			(at 0 0 90)
			(layer "F.Fab")
			(hide yes)
			(effects
				(font
					(size 1.27 1.27)
					(thickness 0.15)
				)
			)
		)
		(property "Description" "SMD Multilayer Ceramic Capacitor, 47 µF, 6.3 V, 0603 [1608 Metric], ± 20%, X5R, GRM Series"
			(at 0 0 90)
			(layer "F.Fab")
			(hide yes)
			(effects
				(font
					(size 1.27 1.27)
					(thickness 0.15)
				)
			)
		)
		(property "Author" "Antmicro"
			(at 337.69 -74.49 0)
			(layer "B.Fab")
			(hide yes)
			(effects
				(font
					(size 1 1)
					(thickness 0.15)
				)
				(justify mirror)
			)
		)
		(property "Capacitance" "47u"
			(at 337.69 -74.49 0)
			(layer "B.Fab")
			(hide yes)
			(effects
				(font
					(size 1 1)
					(thickness 0.15)
				)
				(justify mirror)
			)
		)
		(property "Dielectric" "X7R"
			(at 337.69 -74.49 0)
			(layer "B.Fab")
			(hide yes)
			(effects
				(font
					(size 1 1)
					(thickness 0.15)
				)
				(justify mirror)
			)
		)
		(property "License" "Apache-2.0"
			(at 337.69 -74.49 0)
			(layer "B.Fab")
			(hide yes)
			(effects
				(font
					(size 1 1)
					(thickness 0.15)
				)
				(justify mirror)
			)
		)
		(property "MPN" "GRM188R60J476ME15D"
			(at 337.69 -74.49 0)
			(layer "B.Fab")
			(hide yes)
			(effects
				(font
					(size 1 1)
					(thickness 0.15)
				)
				(justify mirror)
			)
		)
		(property "Manufacturer" "Murata"
			(at 337.69 -74.49 0)
			(layer "B.Fab")
			(hide yes)
			(effects
				(font
					(size 1 1)
					(thickness 0.15)
				)
				(justify mirror)
			)
		)
		(property "Public" ""
			(at 337.69 -74.49 0)
			(layer "B.Fab")
			(hide yes)
			(effects
				(font
					(size 1 1)
					(thickness 0.15)
				)
				(justify mirror)
			)
		)
		(property "Val" "47u"
			(at 337.69 -74.49 0)
			(layer "B.Fab")
			(hide yes)
			(effects
				(font
					(size 1 1)
					(thickness 0.15)
				)
				(justify mirror)
			)
		)
		(property "Voltage" "50V"
			(at 337.69 -74.49 0)
			(layer "B.Fab")
			(hide yes)
			(effects
				(font
					(size 1 1)
					(thickness 0.15)
				)
				(justify mirror)
			)
		)
		(sheetname "/FPGA Supply/")
		(sheetfile "fpga-supply.kicad_sch")
		(attr smd)
		(fp_line
			(start -0.15 -0.4)
			(end 0.15 -0.4)
			(stroke
				(width 0.15)
				(type solid)
			)
			(layer "B.SilkS")
		)
		(fp_line
			(start -0.15 0.4)
			(end 0.15 0.4)
			(stroke
				(width 0.15)
				(type solid)
			)
			(layer "B.SilkS")
		)
		(fp_rect
			(start -1.25 0.65)
			(end 1.25 -0.65)
			(stroke
				(width 0.05)
				(type solid)
			)
			(fill no)
			(layer "B.CrtYd")
		)
		(fp_rect
			(start -0.8 0.4)
			(end 0.8 -0.4)
			(stroke
				(width 0.15)
				(type solid)
			)
			(fill no)
			(layer "B.Fab")
		)
		(fp_text user "License: Apache-2.0"
			(at -1.682 -5.895 270)
			(layer "B.Fab")
			(effects
				(font
					(size 0.7 0.7)
					(thickness 0.15)
				)
				(justify left bottom mirror)
			)
		)
		(fp_text user "Author: Antmicro"
			(at -1.682 -4.894 270)
			(layer "B.Fab")
			(effects
				(font
					(size 0.7 0.7)
					(thickness 0.15)
				)
				(justify left bottom mirror)
			)
		)
		(fp_text user "${REFERENCE}"
			(at -1.682 -3.895 270)
			(layer "B.Fab")
			(effects
				(font
					(size 0.7 0.7)
					(thickness 0.15)
				)
				(justify left bottom mirror)
			)
		)
		(pad "1" smd roundrect
			(at -0.7 0 90)
			(size 0.8 1)
			(layers "B.Cu" "B.Mask" "B.Paste")
			(roundrect_rratio 0.2)
			(net 417 "GND")
			(pintype "passive")
		)
		(pad "2" smd roundrect
			(at 0.7 0 90)
			(size 0.8 1)
			(layers "B.Cu" "B.Mask" "B.Paste")
			(roundrect_rratio 0.2)
			(net 649 "VDD")
			(pintype "passive")
		)
	)
	(footprint "antmicro-footprints:R_0402_1005Metric"
		(layer "B.Cu")
		(at 219.32 154.14 180)
		(descr "Resistor SMD 0402")
		(tags "resistor SMD 0402")
		(property "Reference" "R89"
			(at 0.96 -0.43 0)
			(layer "B.SilkS")
			(effects
				(font
					(size 0.7 0.7)
					(thickness 0.15)
				)
				(justify left bottom mirror)
			)
		)
		(property "Value" "R_50R_0402"
			(at -1.011843 -1.772047 0)
			(layer "B.Fab")
			(hide yes)
			(effects
				(font
					(size 0.7 0.7)
					(thickness 0.15)
				)
				(justify left bottom mirror)
			)
		)
		(property "Datasheet" "https://www.bourns.com/docs/product-datasheets/cr.pdf"
			(at 0 0 180)
			(layer "F.Fab")
			(hide yes)
			(effects
				(font
					(size 1.27 1.27)
					(thickness 0.15)
				)
			)
		)
		(property "Description" "SMD Chip Resistor"
			(at 0 0 180)
			(layer "F.Fab")
			(hide yes)
			(effects
				(font
					(size 1.27 1.27)
					(thickness 0.15)
				)
			)
		)
		(property "Author" "Antmicro"
			(at 438.64 308.28 0)
			(layer "B.Fab")
			(hide yes)
			(effects
				(font
					(size 1 1)
					(thickness 0.15)
				)
				(justify mirror)
			)
		)
		(property "License" "Apache-2.0"
			(at 438.64 308.28 0)
			(layer "B.Fab")
			(hide yes)
			(effects
				(font
					(size 1 1)
					(thickness 0.15)
				)
				(justify mirror)
			)
		)
		(property "MPN" "CR0402-FX-50R0GLF"
			(at 438.64 308.28 0)
			(layer "B.Fab")
			(hide yes)
			(effects
				(font
					(size 1 1)
					(thickness 0.15)
				)
				(justify mirror)
			)
		)
		(property "Manufacturer" "Bourns"
			(at 438.64 308.28 0)
			(layer "B.Fab")
			(hide yes)
			(effects
				(font
					(size 1 1)
					(thickness 0.15)
				)
				(justify mirror)
			)
		)
		(property "Public" ""
			(at 438.64 308.28 0)
			(layer "B.Fab")
			(hide yes)
			(effects
				(font
					(size 1 1)
					(thickness 0.15)
				)
				(justify mirror)
			)
		)
		(property "Tolerance" "1%"
			(at 438.64 308.28 0)
			(layer "B.Fab")
			(hide yes)
			(effects
				(font
					(size 1 1)
					(thickness 0.15)
				)
				(justify mirror)
			)
		)
		(property "Val" "50R"
			(at 438.64 308.28 0)
			(layer "B.Fab")
			(hide yes)
			(effects
				(font
					(size 1 1)
					(thickness 0.15)
				)
				(justify mirror)
			)
		)
		(sheetname "/PCIe/")
		(sheetfile "pcie.kicad_sch")
		(attr smd)
		(fp_rect
			(start -0.925 0.47)
			(end 0.925 -0.47)
			(stroke
				(width 0.05)
				(type default)
			)
			(fill no)
			(layer "B.CrtYd")
		)
		(fp_rect
			(start -0.5 0.25)
			(end 0.5 -0.25)
			(stroke
				(width 0.15)
				(type solid)
			)
			(fill no)
			(layer "B.Fab")
		)
		(fp_text user "Author: Antmicro"
			(at -0.95 -4.169 0)
			(layer "B.Fab")
			(effects
				(font
					(size 0.7 0.7)
					(thickness 0.15)
				)
				(justify left bottom mirror)
			)
		)
		(fp_text user "${REFERENCE}"
			(at -0.95 -3.168 0)
			(layer "B.Fab")
			(effects
				(font
					(size 0.7 0.7)
					(thickness 0.15)
				)
				(justify left bottom mirror)
			)
		)
		(fp_text user "License: Apache-2.0"
			(at -0.95 -5.169 0)
			(layer "B.Fab")
			(effects
				(font
					(size 0.7 0.7)
					(thickness 0.15)
				)
				(justify left bottom mirror)
			)
		)
		(pad "1" smd roundrect
			(at -0.48 0 180)
			(size 0.59 0.64)
			(layers "B.Cu" "B.Mask" "B.Paste")
			(roundrect_rratio 0.25)
			(net 417 "GND")
			(pintype "passive")
		)
		(pad "2" smd roundrect
			(at 0.48 0 180)
			(size 0.59 0.64)
			(layers "B.Cu" "B.Mask" "B.Paste")
			(roundrect_rratio 0.25)
			(net 315 "Net-(U17-CLK1+)")
			(pintype "passive")
		)
	)
	(footprint "antmicro-footprints:R_0603_1608Metric"
		(layer "B.Cu")
		(at 184.25 144.65 -45)
		(descr "Resistor SMD 0603")
		(tags "resistor SMD 0603")
		(property "Reference" "R49"
			(at 3.196123 -1.682914 135)
			(layer "B.SilkS")
			(effects
				(font
					(size 0.7 0.7)
					(thickness 0.15)
				)
				(justify left bottom mirror)
			)
		)
		(property "Value" "R_0R01_0603"
			(at 0 -1.6 135)
			(layer "B.Fab")
			(hide yes)
			(effects
				(font
					(size 0.7 0.7)
					(thickness 0.15)
				)
				(justify left bottom mirror)
			)
		)
		(property "Datasheet" "https://www.bourns.com/docs/product-datasheets/cfn-a.pdf"
			(at 0 0 315)
			(layer "F.Fab")
			(hide yes)
			(effects
				(font
					(size 1.27 1.27)
					(thickness 0.15)
				)
			)
		)
		(property "Description" "SMD Chip Resistor, 10 mohm, ± 1%, 0.5 W, 0603 [1608 Metric], Metal Foil, Current Sensing"
			(at 0 0 315)
			(layer "F.Fab")
			(hide yes)
			(effects
				(font
					(size 1.27 1.27)
					(thickness 0.15)
				)
			)
		)
		(property "Author" "Antmicro"
			(at -48.31742 172.651428 0)
			(layer "B.Fab")
			(hide yes)
			(effects
				(font
					(size 1 1)
					(thickness 0.15)
				)
				(justify mirror)
			)
		)
		(property "License" "Apache-2.0"
			(at -48.31742 172.651428 0)
			(layer "B.Fab")
			(hide yes)
			(effects
				(font
					(size 1 1)
					(thickness 0.15)
				)
				(justify mirror)
			)
		)
		(property "MPN" "CFN0603AFZ-R010ELF"
			(at -48.31742 172.651428 0)
			(layer "B.Fab")
			(hide yes)
			(effects
				(font
					(size 1 1)
					(thickness 0.15)
				)
				(justify mirror)
			)
		)
		(property "Manufacturer" "Bourns"
			(at -48.31742 172.651428 0)
			(layer "B.Fab")
			(hide yes)
			(effects
				(font
					(size 1 1)
					(thickness 0.15)
				)
				(justify mirror)
			)
		)
		(property "Public" ""
			(at -48.31742 172.651428 0)
			(layer "B.Fab")
			(hide yes)
			(effects
				(font
					(size 1 1)
					(thickness 0.15)
				)
				(justify mirror)
			)
		)
		(property "Tolerance" "1%"
			(at -48.31742 172.651428 0)
			(layer "B.Fab")
			(hide yes)
			(effects
				(font
					(size 1 1)
					(thickness 0.15)
				)
				(justify mirror)
			)
		)
		(property "Val" "0R01"
			(at -48.31742 172.651428 0)
			(layer "B.Fab")
			(hide yes)
			(effects
				(font
					(size 1 1)
					(thickness 0.15)
				)
				(justify mirror)
			)
		)
		(sheetname "/Supply/")
		(sheetfile "supply.kicad_sch")
		(attr smd)
		(fp_line
			(start -0.15 0.4)
			(end 0.15 0.4)
			(stroke
				(width 0.15)
				(type solid)
			)
			(layer "B.SilkS")
		)
		(fp_line
			(start -0.15 -0.4)
			(end 0.15 -0.4)
			(stroke
				(width 0.15)
				(type solid)
			)
			(layer "B.SilkS")
		)
		(fp_poly
			(pts
				(xy -1.25 0.65) (xy 1.25 0.65) (xy 1.25 -0.65) (xy -1.25 -0.65)
			)
			(stroke
				(width 0.05)
				(type solid)
			)
			(fill no)
			(layer "B.CrtYd")
		)
		(fp_poly
			(pts
				(xy -0.8 0.4) (xy 0.8 0.4) (xy 0.8 -0.4) (xy -0.8 -0.4)
			)
			(stroke
				(width 0.15)
				(type solid)
			)
			(fill no)
			(layer "B.Fab")
		)
		(fp_text user "${REFERENCE}"
			(at -1.25 -3.898 135)
			(layer "B.Fab")
			(effects
				(font
					(size 0.7 0.7)
					(thickness 0.15)
				)
				(justify left bottom mirror)
			)
		)
		(fp_text user "Author: Antmicro"
			(at -1.25 -4.9 135)
			(layer "B.Fab")
			(effects
				(font
					(size 0.7 0.7)
					(thickness 0.15)
				)
				(justify left bottom mirror)
			)
		)
		(fp_text user "License: Apache-2.0"
			(at -1.249999 -5.9 135)
			(layer "B.Fab")
			(effects
				(font
					(size 0.7 0.7)
					(thickness 0.15)
				)
				(justify left bottom mirror)
			)
		)
		(pad "1" smd roundrect
			(at -0.7 0 315)
			(size 0.8 1)
			(layers "B.Cu" "B.Mask" "B.Paste")
			(roundrect_rratio 0.2)
			(net 409 "/Supply/SENSE4_P")
			(pintype "passive")
		)
		(pad "2" smd roundrect
			(at 0.7 0 315)
			(size 0.8 1)
			(layers "B.Cu" "B.Mask" "B.Paste")
			(roundrect_rratio 0.2)
			(net 96 "+1V2")
			(pintype "passive")
		)
	)
	(footprint "antmicro-footprints:C_0402_1005Metric"
		(layer "B.Cu")
		(at 203.216 148.675)
		(descr "Capacitor SMD 0402")
		(tags "capacitor SMD 0402")
		(property "Reference" "C200"
			(at -0.366 2.225 0)
			(layer "B.SilkS")
			(effects
				(font
					(size 0.7 0.7)
					(thickness 0.15)
				)
				(justify right bottom mirror)
			)
		)
		(property "Value" "C_1u_0402"
			(at -1.022927 -2.155213 0)
			(layer "B.Fab")
			(hide yes)
			(effects
				(font
					(size 0.7 0.7)
					(thickness 0.15)
				)
				(justify right bottom mirror)
			)
		)
		(property "Datasheet" "https://product.tdk.com/en/search/capacitor/ceramic/mlcc/info?part_no=C1005X6S1A105K050BC"
			(at 0 0 0)
			(layer "F.Fab")
			(hide yes)
			(effects
				(font
					(size 1.27 1.27)
					(thickness 0.15)
				)
			)
		)
		(property "Description" "SMD Multilayer Ceramic Capacitor, 1 µF, 10 V, 0402 [1005 Metric], ± 10%, X6S, C"
			(at 0 0 0)
			(layer "F.Fab")
			(hide yes)
			(effects
				(font
					(size 1.27 1.27)
					(thickness 0.15)
				)
			)
		)
		(property "Author" "Antmicro"
			(at 0 0 0)
			(layer "B.Fab")
			(hide yes)
			(effects
				(font
					(size 1 1)
					(thickness 0.15)
				)
				(justify mirror)
			)
		)
		(property "Dielectric" ""
			(at 0 0 0)
			(layer "B.Fab")
			(hide yes)
			(effects
				(font
					(size 1 1)
					(thickness 0.15)
				)
				(justify mirror)
			)
		)
		(property "License" "Apache-2.0"
			(at 0 0 0)
			(layer "B.Fab")
			(hide yes)
			(effects
				(font
					(size 1 1)
					(thickness 0.15)
				)
				(justify mirror)
			)
		)
		(property "MPN" "C1005X6S1A105K050BC"
			(at 0 0 0)
			(layer "B.Fab")
			(hide yes)
			(effects
				(font
					(size 1 1)
					(thickness 0.15)
				)
				(justify mirror)
			)
		)
		(property "Manufacturer" "TDK"
			(at 0 0 0)
			(layer "B.Fab")
			(hide yes)
			(effects
				(font
					(size 1 1)
					(thickness 0.15)
				)
				(justify mirror)
			)
		)
		(property "Public" ""
			(at 0 0 0)
			(layer "B.Fab")
			(hide yes)
			(effects
				(font
					(size 1 1)
					(thickness 0.15)
				)
				(justify mirror)
			)
		)
		(property "Val" "1u"
			(at 0 0 0)
			(layer "B.Fab")
			(hide yes)
			(effects
				(font
					(size 1 1)
					(thickness 0.15)
				)
				(justify mirror)
			)
		)
		(property "Voltage" ""
			(at 0 0 0)
			(layer "B.Fab")
			(hide yes)
			(effects
				(font
					(size 1 1)
					(thickness 0.15)
				)
				(justify mirror)
			)
		)
		(sheetname "/MIPI CrossLink/")
		(sheetfile "crosslink.kicad_sch")
		(attr smd)
		(fp_rect
			(start -0.925 0.47)
			(end 0.925 -0.47)
			(stroke
				(width 0.05)
				(type default)
			)
			(fill no)
			(layer "B.CrtYd")
		)
		(fp_line
			(start -0.494 -0.248)
			(end -0.494 0.25)
			(stroke
				(width 0.15)
				(type solid)
			)
			(layer "B.Fab")
		)
		(fp_line
			(start -0.494 0.25)
			(end 0.504 0.25)
			(stroke
				(width 0.15)
				(type solid)
			)
			(layer "B.Fab")
		)
		(fp_line
			(start 0.504 -0.248)
			(end -0.494 -0.248)
			(stroke
				(width 0.15)
				(type solid)
			)
			(layer "B.Fab")
		)
		(fp_line
			(start 0.504 0.25)
			(end 0.504 -0.248)
			(stroke
				(width 0.15)
				(type solid)
			)
			(layer "B.Fab")
		)
		(fp_text user "Author: Antmicro"
			(at -0.939 -3.399 180)
			(layer "B.Fab")
			(effects
				(font
					(size 0.7 0.7)
					(thickness 0.15)
				)
				(justify left bottom mirror)
			)
		)
		(fp_text user "License: Apache-2.0"
			(at -0.939 -5.799 180)
			(layer "B.Fab")
			(effects
				(font
					(size 0.7 0.7)
					(thickness 0.15)
				)
				(justify left bottom mirror)
			)
		)
		(fp_text user "${REFERENCE}"
			(at -0.939 -4.599 180)
			(layer "B.Fab")
			(effects
				(font
					(size 0.7 0.7)
					(thickness 0.15)
				)
				(justify left bottom mirror)
			)
		)
		(pad "1" smd roundrect
			(at -0.48 0)
			(size 0.59 0.64)
			(layers "B.Cu" "B.Mask" "B.Paste")
			(roundrect_rratio 0.25)
			(net 417 "GND")
			(pintype "passive")
		)
		(pad "2" smd roundrect
			(at 0.48 0)
			(size 0.59 0.64)
			(layers "B.Cu" "B.Mask" "B.Paste")
			(roundrect_rratio 0.25)
			(net 103 "2V5_CL")
			(pintype "passive")
		)
	)
)
